(kicad_pcb
	(version 20260206)
	(generator "pcbnew")
	(generator_version "10.0")
	(general
		(thickness 1.21888)
		(legacy_teardrops no)
	)
	(paper "A4")
	(title_block
		(title "timecard-v7 — TimeCard-DC-V7_EXP.PcbDoc")
		(comment 1 "Time Appliance Project (Time Card) / footprints 42-47 of 160")
	)
	(layers
		(0 "F.Cu" signal "TOP")
		(4 "In1.Cu" signal "SGND")
		(6 "In2.Cu" signal "IN1")
		(8 "In3.Cu" signal "IN2")
		(10 "In4.Cu" signal "SGND1")
		(2 "B.Cu" signal "BOTTOM")
		(9 "F.Adhes" user "F.Adhesive")
		(11 "B.Adhes" user "B.Adhesive")
		(13 "F.Paste" user "Top Paste")
		(15 "B.Paste" user "Bottom Paste")
		(5 "F.SilkS" user "Top Overlay")
		(7 "B.SilkS" user "Bottom Overlay")
		(1 "F.Mask" user "Top Solder")
		(3 "B.Mask" user "Bottom Solder")
		(17 "Dwgs.User" user "User.Drawings")
		(19 "Cmts.User" user "User.Comments")
		(21 "Eco1.User" user "User.Eco1")
		(23 "Eco2.User" user "User.Eco2")
		(25 "Edge.Cuts" user)
		(27 "Margin" user)
		(31 "F.CrtYd" user "Top Courtyard")
		(29 "B.CrtYd" user "Bottom Courtyard")
		(35 "F.Fab" user "Top Component Center")
		(33 "B.Fab" user "Bottom Component Center")
	)
	(footprint "Connectors:PCIE_4LANE_EDGE"
		(layer "F.Cu")
		(at 118.02597 154.3547)
		(property "Reference" "P2"
			(at -12.64987 -0.282755 0)
			(unlocked yes)
			(layer "F.SilkS")
			(hide yes)
			(effects
				(font
					(size 0.762 0.762)
					(thickness 0.2286)
				)
				(justify left bottom)
			)
		)
		(property "Value" "PCIex4"
			(at -5.44907 18.65122 0)
			(unlocked yes)
			(layer "F.SilkS")
			(hide yes)
			(effects
				(font
					(size 1.524 1.524)
					(thickness 0.254)
				)
				(justify left bottom)
			)
		)
		(sheetname "PCIe_JTAG")
		(sheetfile "PCIe_JTAG.kicad_sch")
		(duplicate_pad_numbers_are_jumpers no)
		(pad "A1" smd rect
			(at -16.49984 2.2286)
			(size 0.7112 3.2004)
			(layers "B.Cu" "B.Mask" "B.Paste")
			(net "PRSNT")
		)
		(pad "A2" smd rect
			(at -15.49985 2.7239)
			(size 0.7112 4.191)
			(layers "B.Cu" "B.Mask" "B.Paste")
			(net "+12V_PCIE")
		)
		(pad "A3" smd rect
			(at -14.49985 2.7239)
			(size 0.7112 4.191)
			(layers "B.Cu" "B.Mask" "B.Paste")
			(net "+12V_PCIE")
		)
		(pad "A4" smd rect
			(at -13.49985 2.7239)
			(size 0.7112 4.191)
			(layers "B.Cu" "B.Mask" "B.Paste")
			(net "GND")
		)
		(pad "A5" smd rect
			(at -12.49985 2.7239)
			(size 0.7112 4.191)
			(layers "B.Cu" "B.Mask" "B.Paste")
		)
		(pad "A6" smd rect
			(at -11.49985 2.7239)
			(size 0.7112 4.191)
			(layers "B.Cu" "B.Mask" "B.Paste")
		)
		(pad "A7" smd rect
			(at -10.49986 2.7239)
			(size 0.7112 4.191)
			(layers "B.Cu" "B.Mask" "B.Paste")
		)
		(pad "A8" smd rect
			(at -9.49986 2.7239)
			(size 0.7112 4.191)
			(layers "B.Cu" "B.Mask" "B.Paste")
		)
		(pad "A9" smd rect
			(at -8.49986 2.7239)
			(size 0.7112 4.191)
			(layers "B.Cu" "B.Mask" "B.Paste")
			(net "+3.3V_PCIE")
		)
		(pad "A10" smd rect
			(at -7.49986 2.7239)
			(size 0.7112 4.191)
			(layers "B.Cu" "B.Mask" "B.Paste")
			(net "+3.3V_PCIE")
		)
		(pad "A11" smd rect
			(at -6.49986 2.7239)
			(size 0.7112 4.191)
			(layers "B.Cu" "B.Mask" "B.Paste")
			(net "PCIE_PERST")
		)
		(pad "A12" smd rect
			(at -3.49987 2.7239)
			(size 0.7112 4.191)
			(layers "B.Cu" "B.Mask" "B.Paste")
			(net "GND")
		)
		(pad "A13" smd rect
			(at -2.49987 2.7239)
			(size 0.7112 4.191)
			(layers "B.Cu" "B.Mask" "B.Paste")
			(net "NetC44_1")
		)
		(pad "A14" smd rect
			(at -1.49987 2.7239)
			(size 0.7112 4.191)
			(layers "B.Cu" "B.Mask" "B.Paste")
			(net "NetC45_1")
		)
		(pad "A15" smd rect
			(at -0.49988 2.7239)
			(size 0.7112 4.191)
			(layers "B.Cu" "B.Mask" "B.Paste")
			(net "GND")
		)
		(pad "A16" smd rect
			(at 0.50012 2.7239)
			(size 0.7112 4.191)
			(layers "B.Cu" "B.Mask" "B.Paste")
			(net "NetC46_1")
		)
		(pad "A17" smd rect
			(at 1.50012 2.7239)
			(size 0.7112 4.191)
			(layers "B.Cu" "B.Mask" "B.Paste")
			(net "NetC47_1")
		)
		(pad "A18" smd rect
			(at 2.50012 2.7239)
			(size 0.7112 4.191)
			(layers "B.Cu" "B.Mask" "B.Paste")
			(net "GND")
		)
		(pad "A19" smd rect
			(at 3.50012 2.7239)
			(size 0.7112 4.191)
			(layers "B.Cu" "B.Mask" "B.Paste")
		)
		(pad "A20" smd rect
			(at 4.50011 2.7239)
			(size 0.7112 4.191)
			(layers "B.Cu" "B.Mask" "B.Paste")
			(net "GND")
		)
		(pad "A21" smd rect
			(at 5.50011 2.7239)
			(size 0.7112 4.191)
			(layers "B.Cu" "B.Mask" "B.Paste")
			(net "NetC48_1")
		)
		(pad "A22" smd rect
			(at 6.50011 2.7239)
			(size 0.7112 4.191)
			(layers "B.Cu" "B.Mask" "B.Paste")
			(net "NetC49_1")
		)
		(pad "A23" smd rect
			(at 7.50011 2.7239)
			(size 0.7112 4.191)
			(layers "B.Cu" "B.Mask" "B.Paste")
			(net "GND")
		)
		(pad "A24" smd rect
			(at 8.50011 2.7239)
			(size 0.7112 4.191)
			(layers "B.Cu" "B.Mask" "B.Paste")
			(net "GND")
		)
		(pad "A25" smd rect
			(at 9.5001 2.7239)
			(size 0.7112 4.191)
			(layers "B.Cu" "B.Mask" "B.Paste")
			(net "NetC50_1")
		)
		(pad "A26" smd rect
			(at 10.5001 2.7239)
			(size 0.7112 4.191)
			(layers "B.Cu" "B.Mask" "B.Paste")
			(net "NetC51_1")
		)
		(pad "A27" smd rect
			(at 11.5001 2.7239)
			(size 0.7112 4.191)
			(layers "B.Cu" "B.Mask" "B.Paste")
			(net "GND")
		)
		(pad "A28" smd rect
			(at 12.5001 2.7239)
			(size 0.7112 4.191)
			(layers "B.Cu" "B.Mask" "B.Paste")
			(net "GND")
		)
		(pad "A29" smd rect
			(at 13.5001 2.7239)
			(size 0.7112 4.191)
			(layers "B.Cu" "B.Mask" "B.Paste")
			(net "NetC52_1")
		)
		(pad "A30" smd rect
			(at 14.50009 2.7239)
			(size 0.7112 4.191)
			(layers "B.Cu" "B.Mask" "B.Paste")
			(net "NetC53_1")
		)
		(pad "A31" smd rect
			(at 15.50009 2.7239)
			(size 0.7112 4.191)
			(layers "B.Cu" "B.Mask" "B.Paste")
			(net "GND")
		)
		(pad "A32" smd rect
			(at 16.50009 2.7239)
			(size 0.7112 4.191)
			(layers "B.Cu" "B.Mask" "B.Paste")
		)
		(pad "B1" smd rect
			(at -16.49984 2.7239)
			(size 0.7112 4.191)
			(layers "F.Cu" "F.Mask" "F.Paste")
			(net "+12V_PCIE")
		)
		(pad "B2" smd rect
			(at -15.49985 2.7239)
			(size 0.7112 4.191)
			(layers "F.Cu" "F.Mask" "F.Paste")
			(net "+12V_PCIE")
		)
		(pad "B3" smd rect
			(at -14.49985 2.7239)
			(size 0.7112 4.191)
			(layers "F.Cu" "F.Mask" "F.Paste")
			(net "+12V_PCIE")
		)
		(pad "B4" smd rect
			(at -13.49985 2.7239)
			(size 0.7112 4.191)
			(layers "F.Cu" "F.Mask" "F.Paste")
			(net "GND")
		)
		(pad "B5" smd rect
			(at -12.49985 2.7239)
			(size 0.7112 4.191)
			(layers "F.Cu" "F.Mask" "F.Paste")
		)
		(pad "B6" smd rect
			(at -11.49985 2.7239)
			(size 0.7112 4.191)
			(layers "F.Cu" "F.Mask" "F.Paste")
		)
		(pad "B7" smd rect
			(at -10.49986 2.7239)
			(size 0.7112 4.191)
			(layers "F.Cu" "F.Mask" "F.Paste")
			(net "GND")
		)
		(pad "B8" smd rect
			(at -9.49986 2.7239)
			(size 0.7112 4.191)
			(layers "F.Cu" "F.Mask" "F.Paste")
			(net "+3.3V_PCIE")
		)
		(pad "B9" smd rect
			(at -8.49986 2.7239)
			(size 0.7112 4.191)
			(layers "F.Cu" "F.Mask" "F.Paste")
		)
		(pad "B10" smd rect
			(at -7.49986 2.7239)
			(size 0.7112 4.191)
			(layers "F.Cu" "F.Mask" "F.Paste")
		)
		(pad "B11" smd rect
			(at -6.49986 2.7239)
			(size 0.7112 4.191)
			(layers "F.Cu" "F.Mask" "F.Paste")
		)
		(pad "B12" smd rect
			(at -3.49987 2.7239)
			(size 0.7112 4.191)
			(layers "F.Cu" "F.Mask" "F.Paste")
		)
		(pad "B13" smd rect
			(at -2.49987 2.7239)
			(size 0.7112 4.191)
			(layers "F.Cu" "F.Mask" "F.Paste")
			(net "GND")
		)
		(pad "B14" smd rect
			(at -1.49987 2.7239)
			(size 0.7112 4.191)
			(layers "F.Cu" "F.Mask" "F.Paste")
			(net "PCIE_RX0_P")
		)
		(pad "B15" smd rect
			(at -0.49988 2.7239)
			(size 0.7112 4.191)
			(layers "F.Cu" "F.Mask" "F.Paste")
			(net "PCIE_RX0_N")
		)
		(pad "B16" smd rect
			(at 0.50012 2.7239)
			(size 0.7112 4.191)
			(layers "F.Cu" "F.Mask" "F.Paste")
			(net "GND")
		)
		(pad "B17" smd rect
			(at 1.50012 2.7239)
			(size 0.7112 4.191)
			(layers "F.Cu" "F.Mask" "F.Paste")
			(net "NetP2_B17")
		)
		(pad "B18" smd rect
			(at 2.50012 2.7239)
			(size 0.7112 4.191)
			(layers "F.Cu" "F.Mask" "F.Paste")
			(net "GND")
		)
		(pad "B19" smd rect
			(at 3.50012 2.7239)
			(size 0.7112 4.191)
			(layers "F.Cu" "F.Mask" "F.Paste")
			(net "PCIE_RX1_P")
		)
		(pad "B20" smd rect
			(at 4.50011 2.7239)
			(size 0.7112 4.191)
			(layers "F.Cu" "F.Mask" "F.Paste")
			(net "PCIE_RX1_N")
		)
		(pad "B21" smd rect
			(at 5.50011 2.7239)
			(size 0.7112 4.191)
			(layers "F.Cu" "F.Mask" "F.Paste")
			(net "GND")
		)
		(pad "B22" smd rect
			(at 6.50011 2.7239)
			(size 0.7112 4.191)
			(layers "F.Cu" "F.Mask" "F.Paste")
			(net "GND")
		)
		(pad "B23" smd rect
			(at 7.50011 2.7239)
			(size 0.7112 4.191)
			(layers "F.Cu" "F.Mask" "F.Paste")
			(net "PCIE_RX2_P")
		)
		(pad "B24" smd rect
			(at 8.50011 2.7239)
			(size 0.7112 4.191)
			(layers "F.Cu" "F.Mask" "F.Paste")
			(net "PCIE_RX2_N")
		)
		(pad "B25" smd rect
			(at 9.5001 2.7239)
			(size 0.7112 4.191)
			(layers "F.Cu" "F.Mask" "F.Paste")
			(net "GND")
		)
		(pad "B26" smd rect
			(at 10.5001 2.7239)
			(size 0.7112 4.191)
			(layers "F.Cu" "F.Mask" "F.Paste")
			(net "GND")
		)
		(pad "B27" smd rect
			(at 11.5001 2.7239)
			(size 0.7112 4.191)
			(layers "F.Cu" "F.Mask" "F.Paste")
			(net "PCIE_RX3_P")
		)
		(pad "B28" smd rect
			(at 12.5001 2.7239)
			(size 0.7112 4.191)
			(layers "F.Cu" "F.Mask" "F.Paste")
			(net "PCIE_RX3_N")
		)
		(pad "B29" smd rect
			(at 13.5001 2.7239)
			(size 0.7112 4.191)
			(layers "F.Cu" "F.Mask" "F.Paste")
			(net "GND")
		)
		(pad "B30" smd rect
			(at 14.50009 2.7239)
			(size 0.7112 4.191)
			(layers "F.Cu" "F.Mask" "F.Paste")
		)
		(pad "B31" smd rect
			(at 15.50009 2.2286)
			(size 0.7112 3.2004)
			(layers "F.Cu" "F.Mask" "F.Paste")
			(net "NetP2_B31")
		)
		(pad "B32" smd rect
			(at 16.50009 2.7239)
			(size 0.7112 4.191)
			(layers "F.Cu" "F.Mask" "F.Paste")
			(net "GND")
		)
	)
	(footprint "Vault:RESC3116X65X50ML20T20"
		(layer "F.Cu")
		(at 156.0261 89.7162)
		(property "Reference" "R47"
			(at 4.6286 -0.373069 0)
			(unlocked yes)
			(layer "F.SilkS")
			(effects
				(font
					(size 0.762 0.762)
					(thickness 0.2286)
				)
			)
		)
		(property "Value" "DNI_0_5%_1206"
			(at 7.29942 3.318002 0)
			(unlocked yes)
			(layer "F.SilkS")
			(hide yes)
			(effects
				(font
					(size 1.524 1.524)
					(thickness 0.254)
				)
			)
		)
		(sheetname "MAC")
		(sheetfile "MAC.kicad_sch")
		(duplicate_pad_numbers_are_jumpers no)
		(fp_line
			(start -0.35 -0.85)
			(end 0.35 -0.85)
			(stroke
				(width 0.2)
				(type solid)
			)
			(layer "F.SilkS")
		)
		(fp_line
			(start -0.35 0.85)
			(end 0.35 0.85)
			(stroke
				(width 0.2)
				(type solid)
			)
			(layer "F.SilkS")
		)
		(pad "1" smd rect
			(at -1.475 0 90)
			(size 1.9 1.45)
			(layers "F.Cu" "F.Mask" "F.Paste")
			(net "MAC_VCC")
		)
		(pad "2" smd rect
			(at 1.475 0 90)
			(size 1.9 1.45)
			(layers "F.Cu" "F.Mask" "F.Paste")
			(net "+3.3V")
		)
	)
	(footprint "Capacitors:CAPC2012X14N"
		(layer "F.Cu")
		(at 227.8261 115.5162 90)
		(property "Reference" "C1"
			(at 2.25 0.343345 90)
			(unlocked yes)
			(layer "F.SilkS")
			(effects
				(font
					(size 0.762 0.762)
					(thickness 0.2286)
				)
				(justify left bottom)
			)
		)
		(property "Value" "CAP_0805_10UF_25V"
			(at -3.52679 -1.5875 0)
			(unlocked yes)
			(layer "F.SilkS")
			(hide yes)
			(effects
				(font
					(size 1.524 1.524)
					(thickness 0.254)
				)
				(justify left bottom)
			)
		)
		(sheetname "POWER")
		(sheetfile "POWER.kicad_sch")
		(duplicate_pad_numbers_are_jumpers no)
		(fp_line
			(start -0.762 -0.9652)
			(end 0.762 -0.9652)
			(stroke
				(width 0.1524)
				(type solid)
			)
			(layer "F.SilkS")
		)
		(fp_line
			(start -0.762 0.9652)
			(end 0.762 0.9652)
			(stroke
				(width 0.1524)
				(type solid)
			)
			(layer "F.SilkS")
		)
		(pad "1" smd rect
			(at -0.9 0 180)
			(size 1.45 1.15)
			(layers "F.Cu" "F.Mask" "F.Paste")
			(net "+12V")
		)
		(pad "2" smd rect
			(at 0.9 0 180)
			(size 1.45 1.15)
			(layers "F.Cu" "F.Mask" "F.Paste")
			(net "GND")
		)
	)
	(footprint "Vault:CAPC1608X87X45ML20T05"
		(layer "F.Cu")
		(at 125.1261 85.0786 -90)
		(property "Reference" "C24"
			(at -0.3338 -1.273069 270)
			(unlocked yes)
			(layer "F.SilkS")
			(effects
				(font
					(size 0.762 0.762)
					(thickness 0.2286)
				)
			)
		)
		(property "Value" "0.1uF"
			(at 2.09443 2.657602 270)
			(unlocked yes)
			(layer "F.SilkS")
			(hide yes)
			(effects
				(font
					(size 1.524 1.524)
					(thickness 0.254)
				)
			)
		)
		(sheetname "MAC")
		(sheetfile "MAC.kicad_sch")
		(duplicate_pad_numbers_are_jumpers no)
		(pad "1" smd rect
			(at -0.7 0)
			(size 1.1 1.05)
			(layers "F.Cu" "F.Mask" "F.Paste")
			(net "+3.3V")
		)
		(pad "2" smd rect
			(at 0.7 0)
			(size 1.1 1.05)
			(layers "F.Cu" "F.Mask" "F.Paste")
			(net "GND")
		)
	)
	(footprint "Vault:FP-STPS5L60S-MFG"
		(layer "F.Cu")
		(at 234.0261 125.4162 -90)
		(property "Reference" "D19"
			(at 0.454005 -4.446148 270)
			(unlocked yes)
			(layer "F.SilkS")
			(effects
				(font
					(size 1.524 1.524)
					(thickness 0.254)
				)
			)
		)
		(property "Value" "STPS5L60S"
			(at -6.518402 3.795165 180)
			(unlocked yes)
			(layer "F.SilkS")
			(hide yes)
			(effects
				(font
					(size 1.524 1.524)
					(thickness 0.254)
				)
			)
		)
		(sheetname "POWER")
		(sheetfile "POWER.kicad_sch")
		(duplicate_pad_numbers_are_jumpers no)
		(fp_line
			(start -3.575 3.125)
			(end -3.575 2.025)
			(stroke
				(width 0.2)
				(type solid)
			)
			(layer "F.SilkS")
		)
		(fp_line
			(start 3.575 3.125)
			(end -3.575 3.125)
			(stroke
				(width 0.2)
				(type solid)
			)
			(layer "F.SilkS")
		)
		(fp_line
			(start 3.575 3.125)
			(end 3.575 2.025)
			(stroke
				(width 0.2)
				(type solid)
			)
			(layer "F.SilkS")
		)
		(fp_line
			(start -3.575 -2.025)
			(end -3.575 -3.125)
			(stroke
				(width 0.2)
				(type solid)
			)
			(layer "F.SilkS")
		)
		(fp_line
			(start 3.575 -2.025)
			(end 3.575 -3.125)
			(stroke
				(width 0.2)
				(type solid)
			)
			(layer "F.SilkS")
		)
		(fp_line
			(start 3.575 -3.125)
			(end -3.575 -3.125)
			(stroke
				(width 0.2)
				(type solid)
			)
			(layer "F.SilkS")
		)
		(fp_circle
			(center -4.7 -0.025)
			(end -4.825 -0.025)
			(stroke
				(width 0.25)
				(type solid)
			)
			(fill no)
			(layer "F.SilkS")
		)
		(fp_line
			(start -4.195 3.225)
			(end -4.195 -3.225)
			(stroke
				(width 0.2)
				(type solid)
			)
			(layer "F.CrtYd")
		)
		(fp_line
			(start 4.195 3.225)
			(end -4.195 3.225)
			(stroke
				(width 0.2)
				(type solid)
			)
			(layer "F.CrtYd")
		)
		(fp_line
			(start 4.195 3.225)
			(end 4.195 -3.225)
			(stroke
				(width 0.2)
				(type solid)
			)
			(layer "F.CrtYd")
		)
		(fp_line
			(start 4.195 -3.225)
			(end -4.195 -3.225)
			(stroke
				(width 0.2)
				(type solid)
			)
			(layer "F.CrtYd")
		)
		(fp_line
			(start -4.195 3.225)
			(end -4.195 -3.225)
			(stroke
				(width 0.2)
				(type solid)
			)
			(layer "F.Fab")
		)
		(fp_line
			(start 4.195 3.225)
			(end -4.195 3.225)
			(stroke
				(width 0.2)
				(type solid)
			)
			(layer "F.Fab")
		)
		(fp_line
			(start 4.195 3.225)
			(end 4.195 -3.225)
			(stroke
				(width 0.2)
				(type solid)
			)
			(layer "F.Fab")
		)
		(fp_line
			(start 0 0.5)
			(end 0 -0.5)
			(stroke
				(width 0.1)
				(type solid)
			)
			(layer "F.Fab")
		)
		(fp_line
			(start 0.5 0)
			(end -0.5 0)
			(stroke
				(width 0.1)
				(type solid)
			)
			(layer "F.Fab")
		)
		(fp_line
			(start 4.195 -3.225)
			(end -4.195 -3.225)
			(stroke
				(width 0.2)
				(type solid)
			)
			(layer "F.Fab")
		)
		(fp_text user "${REFERENCE}"
			(at -0.00001 0.09602 270)
			(unlocked yes)
			(layer "F.Fab")
			(effects
				(font
					(face "Arial")
					(size 0.63 0.63)
					(thickness 0.1)
				)
				(justify left bottom)
			)
		)
		(pad "1" smd rect
			(at -3.325 0 270)
			(size 1.54 3.14)
			(layers "F.Cu" "F.Mask" "F.Paste")
			(net "NetD12_1")
			(solder_mask_margin 0)
			(solder_paste_margin 0)
		)
		(pad "2" smd rect
			(at 3.325 0 270)
			(size 1.54 3.14)
			(layers "F.Cu" "F.Mask" "F.Paste")
			(net "+12V_PCIE")
			(solder_mask_margin 0)
			(solder_paste_margin 0)
		)
	)
	(footprint "SamacSys:SOP50P310X90-8N"
		(layer "F.Cu")
		(at 82.1261 136.1162 180)
		(property "Reference" "U16"
			(at 0.2286 2.026931 180)
			(unlocked yes)
			(layer "F.SilkS")
			(effects
				(font
					(size 0.762 0.762)
					(thickness 0.2286)
				)
			)
		)
		(property "Value" "NC7WV125K8X"
			(at 6.233115 2.911602 180)
			(unlocked yes)
			(layer "F.SilkS")
			(hide yes)
			(effects
				(font
					(size 1.524 1.524)
					(thickness 0.254)
				)
			)
		)
		(sheetname "USER_IO")
		(sheetfile "USER_IO.kicad_sch")
		(duplicate_pad_numbers_are_jumpers no)
		(fp_line
			(start 0.8 1)
			(end -0.8 1)
			(stroke
				(width 0.2)
				(type solid)
			)
			(layer "F.SilkS")
		)
		(fp_line
			(start 0.8 -1)
			(end 0.8 1)
			(stroke
				(width 0.2)
				(type solid)
			)
			(layer "F.SilkS")
		)
		(fp_line
			(start 0.8 -1)
			(end -0.8 -1)
			(stroke
				(width 0.2)
				(type solid)
			)
			(layer "F.SilkS")
		)
		(fp_line
			(start -0.8 -1)
			(end -0.8 1)
			(stroke
				(width 0.2)
				(type solid)
			)
			(layer "F.SilkS")
		)
		(fp_line
			(start -1.15 -1.25)
			(end -2 -1.25)
			(stroke
				(width 0.2)
				(type solid)
			)
			(layer "F.SilkS")
		)
		(pad "1" smd rect
			(at -1.575 -0.75 180)
			(size 0.85 0.3)
			(layers "F.Cu" "F.Mask" "F.Paste")
			(net "ANT4_IO_OUT")
		)
		(pad "2" smd rect
			(at -1.575 -0.25 180)
			(size 0.85 0.3)
			(layers "F.Cu" "F.Mask" "F.Paste")
			(net "ANT4_OUT")
		)
		(pad "3" smd rect
			(at -1.575 0.25 180)
			(size 0.85 0.3)
			(layers "F.Cu" "F.Mask" "F.Paste")
			(net "ANT4_IN")
		)
		(pad "4" smd rect
			(at -1.575 0.75 180)
			(size 0.85 0.3)
			(layers "F.Cu" "F.Mask" "F.Paste")
			(net "GND")
		)
		(pad "5" smd rect
			(at 1.575 0.75 180)
			(size 0.85 0.3)
			(layers "F.Cu" "F.Mask" "F.Paste")
			(net "NetR34_1")
		)
		(pad "6" smd rect
			(at 1.575 0.25 180)
			(size 0.85 0.3)
			(layers "F.Cu" "F.Mask" "F.Paste")
			(net "NetR34_1")
		)
		(pad "7" smd rect
			(at 1.575 -0.25 180)
			(size 0.85 0.3)
			(layers "F.Cu" "F.Mask" "F.Paste")
			(net "ANT4_IO_IN")
		)
		(pad "8" smd rect
			(at 1.575 -0.75 180)
			(size 0.85 0.3)
			(layers "F.Cu" "F.Mask" "F.Paste")
			(net "+3.3V")
		)
	)
)
